(kicad_pcb
	(version 20260206)
	(generator "pcbnew")
	(generator_version "10.0")
	(general
		(thickness 1.6)
		(legacy_teardrops no)
	)
	(paper "A4")
	(title_block
		(title "01162023_DA0F0TEBIF0_F0T_Expander_BD_F_brd_V02_OCP.brd")
		(comment 1 "Grand Teton / footprint 4451 of 9728 (PEX3), pads 2120-2237 of 2397")
	)
	(layers
		(0 "F.Cu" signal "TOP")
		(4 "In1.Cu" signal "GND")
		(6 "In2.Cu" signal "VCC")
		(8 "In3.Cu" signal "VCC1")
		(10 "In4.Cu" signal "GND1")
		(12 "In5.Cu" signal "IN1")
		(14 "In6.Cu" signal "GND2")
		(16 "In7.Cu" signal "IN2")
		(18 "In8.Cu" signal "GND3")
		(20 "In9.Cu" signal "IN3")
		(22 "In10.Cu" signal "GND4")
		(24 "In11.Cu" signal "IN4")
		(26 "In12.Cu" signal "GND5")
		(28 "In13.Cu" signal "IN5")
		(30 "In14.Cu" signal "GND6")
		(32 "In15.Cu" signal "IN6")
		(34 "In16.Cu" signal "GND7")
		(2 "B.Cu" signal "BOTTOM")
		(9 "F.Adhes" user "F.Adhesive")
		(11 "B.Adhes" user "B.Adhesive")
		(13 "F.Paste" user "Package Geometry/Pastemask Top")
		(15 "B.Paste" user "Package Geometry/Pastemask Bottom")
		(5 "F.SilkS" user "Ref Des/Silkscreen Top")
		(7 "B.SilkS" user "Ref Des/Silkscreen Bottom")
		(1 "F.Mask" user "Board Geometry/Soldermask Top")
		(3 "B.Mask" user "Board Geometry/Soldermask Bottom")
		(17 "Dwgs.User" user "User.Drawings")
		(19 "Cmts.User" user "User.Comments")
		(21 "Eco1.User" user "User.Eco1")
		(23 "Eco2.User" user "User.Eco2")
		(25 "Edge.Cuts" user "Board Geometry/Outline")
		(27 "Margin" user)
		(31 "F.CrtYd" user "Package Geometry/Place Bound Top")
		(29 "B.CrtYd" user "Package Geometry/Place Bound Bottom")
		(35 "F.Fab" user "Ref Des/Assembly Top")
		(33 "B.Fab" user "Ref Des/Assembly Bottom")
	)
	(footprint ""
		(layer "F.Cu")
		(at 407.949908 -295.89984)
		(property "Reference" "PEX3"
			(at -3.358642 35.5727 0)
			(unlocked yes)
			(layer "F.SilkS")
			(effects
				(font
					(size 2.032 1.524)
					(thickness 0.1524)
				)
				(justify left)
			)
		)
		(property "Value" ""
			(at 0 0 0)
			(layer "F.Fab")
			(effects
				(font
					(size 1.27 1.27)
				)
			)
		)
		(duplicate_pad_numbers_are_jumpers no)
		(pad "R17" smd circle
			(at -7.599934 -9.500108)
			(size 0.4572 0.4572)
			(layers "F.Cu" "F.Mask" "F.Paste")
			(net "GND")
		)
		(pad "R18" smd circle
			(at -6.649974 -9.500108)
			(size 0.4572 0.4572)
			(layers "F.Cu" "F.Mask" "F.Paste")
			(net "GND")
		)
		(pad "R19" smd circle
			(at -5.700014 -9.500108)
			(size 0.4572 0.4572)
			(layers "F.Cu" "F.Mask" "F.Paste")
			(net "GND")
		)
		(pad "R20" smd circle
			(at -4.750054 -9.500108)
			(size 0.4572 0.4572)
			(layers "F.Cu" "F.Mask" "F.Paste")
			(net "GND")
		)
		(pad "R21" smd circle
			(at -3.800094 -9.500108)
			(size 0.4572 0.4572)
			(layers "F.Cu" "F.Mask" "F.Paste")
			(net "GND")
		)
		(pad "R22" smd circle
			(at -2.84988 -9.500108)
			(size 0.4572 0.4572)
			(layers "F.Cu" "F.Mask" "F.Paste")
			(net "GND")
		)
		(pad "R23" smd circle
			(at -1.89992 -9.500108)
			(size 0.4572 0.4572)
			(layers "F.Cu" "F.Mask" "F.Paste")
			(net "GND")
		)
		(pad "R24" smd circle
			(at -0.94996 -9.500108)
			(size 0.4572 0.4572)
			(layers "F.Cu" "F.Mask" "F.Paste")
			(net "GND")
		)
		(pad "R25" smd circle
			(at 0 -9.500108)
			(size 0.4572 0.4572)
			(layers "F.Cu" "F.Mask" "F.Paste")
			(net "GND")
		)
		(pad "R26" smd circle
			(at 0.94996 -9.500108)
			(size 0.4572 0.4572)
			(layers "F.Cu" "F.Mask" "F.Paste")
			(net "GND")
		)
		(pad "R27" smd circle
			(at 1.89992 -9.500108)
			(size 0.4572 0.4572)
			(layers "F.Cu" "F.Mask" "F.Paste")
			(net "GND")
		)
		(pad "R28" smd circle
			(at 2.84988 -9.500108)
			(size 0.4572 0.4572)
			(layers "F.Cu" "F.Mask" "F.Paste")
			(net "GND")
		)
		(pad "R29" smd circle
			(at 3.800094 -9.500108)
			(size 0.4572 0.4572)
			(layers "F.Cu" "F.Mask" "F.Paste")
			(net "GND")
		)
		(pad "R30" smd circle
			(at 4.750054 -9.500108)
			(size 0.4572 0.4572)
			(layers "F.Cu" "F.Mask" "F.Paste")
			(net "GND")
		)
		(pad "R31" smd circle
			(at 5.700014 -9.500108)
			(size 0.4572 0.4572)
			(layers "F.Cu" "F.Mask" "F.Paste")
			(net "GND")
		)
		(pad "R32" smd circle
			(at 6.649974 -9.500108)
			(size 0.4572 0.4572)
			(layers "F.Cu" "F.Mask" "F.Paste")
			(net "GND")
		)
		(pad "R33" smd circle
			(at 7.599934 -9.500108)
			(size 0.4572 0.4572)
			(layers "F.Cu" "F.Mask" "F.Paste")
			(net "GND")
		)
		(pad "R34" smd circle
			(at 8.549894 -9.500108)
			(size 0.4572 0.4572)
			(layers "F.Cu" "F.Mask" "F.Paste")
			(net "GND")
		)
		(pad "R35" smd circle
			(at 9.500108 -9.500108)
			(size 0.4572 0.4572)
			(layers "F.Cu" "F.Mask" "F.Paste")
			(net "GND")
		)
		(pad "R36" smd circle
			(at 10.450068 -9.500108)
			(size 0.4572 0.4572)
			(layers "F.Cu" "F.Mask" "F.Paste")
			(net "Net_534")
		)
		(pad "R37" smd circle
			(at 11.400028 -9.500108)
			(size 0.4572 0.4572)
			(layers "F.Cu" "F.Mask" "F.Paste")
			(net "GND")
		)
		(pad "R38" smd circle
			(at 12.349988 -9.500108)
			(size 0.4572 0.4572)
			(layers "F.Cu" "F.Mask" "F.Paste")
			(net "Net_5408")
		)
		(pad "R39" smd circle
			(at 13.299948 -9.500108)
			(size 0.4572 0.4572)
			(layers "F.Cu" "F.Mask" "F.Paste")
			(net "Net_5402")
		)
		(pad "R40" smd circle
			(at 14.249908 -9.500108)
			(size 0.4572 0.4572)
			(layers "F.Cu" "F.Mask" "F.Paste")
			(net "GND")
		)
		(pad "R41" smd circle
			(at 15.200122 -9.500108)
			(size 0.4572 0.4572)
			(layers "F.Cu" "F.Mask" "F.Paste")
			(net "GND")
		)
		(pad "R42" smd circle
			(at 16.150082 -9.500108)
			(size 0.4572 0.4572)
			(layers "F.Cu" "F.Mask" "F.Paste")
			(net "GND")
		)
		(pad "R43" smd circle
			(at 17.100042 -9.500108)
			(size 0.4572 0.4572)
			(layers "F.Cu" "F.Mask" "F.Paste")
			(net "P5E_PEX3_STN4_TX_DP<65>")
		)
		(pad "R44" smd circle
			(at 18.050002 -9.500108)
			(size 0.4572 0.4572)
			(layers "F.Cu" "F.Mask" "F.Paste")
			(net "P5E_PEX3_STN4_TX_DN<65>")
		)
		(pad "R45" smd circle
			(at 18.999962 -9.500108)
			(size 0.4572 0.4572)
			(layers "F.Cu" "F.Mask" "F.Paste")
			(net "GND")
		)
		(pad "R46" smd circle
			(at 19.949922 -9.500108)
			(size 0.4572 0.4572)
			(layers "F.Cu" "F.Mask" "F.Paste")
			(net "P5E_PEX3_STN4_RX_DP<65>")
		)
		(pad "R47" smd circle
			(at 20.899882 -9.500108)
			(size 0.4572 0.4572)
			(layers "F.Cu" "F.Mask" "F.Paste")
			(net "P5E_PEX3_STN4_RX_DN<65>")
		)
		(pad "R48" smd circle
			(at 21.850096 -9.500108)
			(size 0.4572 0.4572)
			(layers "F.Cu" "F.Mask" "F.Paste")
			(net "GND")
		)
		(pad "R49" smd circle
			(at 22.800056 -9.500108)
			(size 0.4572 0.4572)
			(layers "F.Cu" "F.Mask" "F.Paste")
			(net "GND")
		)
		(pad "T1" smd circle
			(at -22.800056 -8.549894)
			(size 0.4572 0.4572)
			(layers "F.Cu" "F.Mask" "F.Paste")
			(net "P5E_PEX3_STN7_RX_DN<115>")
		)
		(pad "T2" smd circle
			(at -21.850096 -8.549894)
			(size 0.4572 0.4572)
			(layers "F.Cu" "F.Mask" "F.Paste")
			(net "P5E_PEX3_STN7_RX_DP<115>")
		)
		(pad "T3" smd circle
			(at -20.899882 -8.549894)
			(size 0.4572 0.4572)
			(layers "F.Cu" "F.Mask" "F.Paste")
			(net "GND")
		)
		(pad "T4" smd circle
			(at -19.949922 -8.549894)
			(size 0.4572 0.4572)
			(layers "F.Cu" "F.Mask" "F.Paste")
			(net "GND")
		)
		(pad "T5" smd circle
			(at -18.999962 -8.549894)
			(size 0.4572 0.4572)
			(layers "F.Cu" "F.Mask" "F.Paste")
			(net "GND")
		)
		(pad "T6" smd circle
			(at -18.050002 -8.549894)
			(size 0.4572 0.4572)
			(layers "F.Cu" "F.Mask" "F.Paste")
			(net "GND")
		)
		(pad "T7" smd circle
			(at -17.100042 -8.549894)
			(size 0.4572 0.4572)
			(layers "F.Cu" "F.Mask" "F.Paste")
			(net "GND")
		)
		(pad "T8" smd circle
			(at -16.150082 -8.549894)
			(size 0.4572 0.4572)
			(layers "F.Cu" "F.Mask" "F.Paste")
			(net "P5E_PEX3_STN7_TX_DN<115>")
		)
		(pad "T9" smd circle
			(at -15.200122 -8.549894)
			(size 0.4572 0.4572)
			(layers "F.Cu" "F.Mask" "F.Paste")
			(net "P5E_PEX3_STN7_TX_DP<115>")
		)
		(pad "T10" smd circle
			(at -14.249908 -8.549894)
			(size 0.4572 0.4572)
			(layers "F.Cu" "F.Mask" "F.Paste")
			(net "GND")
		)
		(pad "T11" smd circle
			(at -13.299948 -8.549894)
			(size 0.4572 0.4572)
			(layers "F.Cu" "F.Mask" "F.Paste")
			(net "GND")
		)
		(pad "T12" smd circle
			(at -12.349988 -8.549894)
			(size 0.4572 0.4572)
			(layers "F.Cu" "F.Mask" "F.Paste")
			(net "GND")
		)
		(pad "T13" smd circle
			(at -11.400028 -8.549894)
			(size 0.4572 0.4572)
			(layers "F.Cu" "F.Mask" "F.Paste")
			(net "GND")
		)
		(pad "T14" smd circle
			(at -10.450068 -8.549894)
			(size 0.4572 0.4572)
			(layers "F.Cu" "F.Mask" "F.Paste")
			(net "Net_542")
		)
		(pad "T15" smd circle
			(at -9.500108 -8.549894)
			(size 0.4572 0.4572)
			(layers "F.Cu" "F.Mask" "F.Paste")
			(net "GND")
		)
		(pad "T16" smd circle
			(at -8.549894 -8.549894)
			(size 0.4572 0.4572)
			(layers "F.Cu" "F.Mask" "F.Paste")
			(net "P1V25_SERDES_VDDPLL_PEX3")
		)
		(pad "T17" smd circle
			(at -7.599934 -8.549894)
			(size 0.4572 0.4572)
			(layers "F.Cu" "F.Mask" "F.Paste")
			(net "P1V25_SERDES_VDDPLL_PEX3")
		)
		(pad "T18" smd circle
			(at -6.649974 -8.549894)
			(size 0.4572 0.4572)
			(layers "F.Cu" "F.Mask" "F.Paste")
			(net "P1V25_SERDES_VDDPLL_PEX3")
		)
		(pad "T19" smd circle
			(at -5.700014 -8.549894)
			(size 0.4572 0.4572)
			(layers "F.Cu" "F.Mask" "F.Paste")
			(net "P1V25_SERDES_VDDPLL_PEX3")
		)
		(pad "T20" smd circle
			(at -4.750054 -8.549894)
			(size 0.4572 0.4572)
			(layers "F.Cu" "F.Mask" "F.Paste")
			(net "P1V25_SERDES_VDDPLL_PEX3")
		)
		(pad "T21" smd circle
			(at -3.800094 -8.549894)
			(size 0.4572 0.4572)
			(layers "F.Cu" "F.Mask" "F.Paste")
			(net "P1V25_SERDES_VDDPLL_PEX3")
		)
		(pad "T22" smd circle
			(at -2.84988 -8.549894)
			(size 0.4572 0.4572)
			(layers "F.Cu" "F.Mask" "F.Paste")
			(net "P1V25_SERDES_VDDPLL_PEX3")
		)
		(pad "T23" smd circle
			(at -1.89992 -8.549894)
			(size 0.4572 0.4572)
			(layers "F.Cu" "F.Mask" "F.Paste")
			(net "P1V25_SERDES_VDDPLL_PEX3")
		)
		(pad "T24" smd circle
			(at -0.94996 -8.549894)
			(size 0.4572 0.4572)
			(layers "F.Cu" "F.Mask" "F.Paste")
			(net "P1V25_SERDES_VDDPLL_PEX3")
		)
		(pad "T25" smd circle
			(at 0 -8.549894)
			(size 0.4572 0.4572)
			(layers "F.Cu" "F.Mask" "F.Paste")
			(net "P1V25_SERDES_VDDPLL_PEX3")
		)
		(pad "T26" smd circle
			(at 0.94996 -8.549894)
			(size 0.4572 0.4572)
			(layers "F.Cu" "F.Mask" "F.Paste")
			(net "P1V25_SERDES_VDDPLL_PEX3")
		)
		(pad "T27" smd circle
			(at 1.89992 -8.549894)
			(size 0.4572 0.4572)
			(layers "F.Cu" "F.Mask" "F.Paste")
			(net "P1V25_SERDES_VDDPLL_PEX3")
		)
		(pad "T28" smd circle
			(at 2.84988 -8.549894)
			(size 0.4572 0.4572)
			(layers "F.Cu" "F.Mask" "F.Paste")
			(net "P1V25_SERDES_VDDPLL_PEX3")
		)
		(pad "T29" smd circle
			(at 3.800094 -8.549894)
			(size 0.4572 0.4572)
			(layers "F.Cu" "F.Mask" "F.Paste")
			(net "P1V25_SERDES_VDDPLL_PEX3")
		)
		(pad "T30" smd circle
			(at 4.750054 -8.549894)
			(size 0.4572 0.4572)
			(layers "F.Cu" "F.Mask" "F.Paste")
			(net "P1V25_SERDES_VDDPLL_PEX3")
		)
		(pad "T31" smd circle
			(at 5.700014 -8.549894)
			(size 0.4572 0.4572)
			(layers "F.Cu" "F.Mask" "F.Paste")
			(net "P1V25_SERDES_VDDPLL_PEX3")
		)
		(pad "T32" smd circle
			(at 6.649974 -8.549894)
			(size 0.4572 0.4572)
			(layers "F.Cu" "F.Mask" "F.Paste")
			(net "P1V25_SERDES_VDDPLL_PEX3")
		)
		(pad "T33" smd circle
			(at 7.599934 -8.549894)
			(size 0.4572 0.4572)
			(layers "F.Cu" "F.Mask" "F.Paste")
			(net "P1V25_SERDES_VDDPLL_PEX3")
		)
		(pad "T34" smd circle
			(at 8.549894 -8.549894)
			(size 0.4572 0.4572)
			(layers "F.Cu" "F.Mask" "F.Paste")
			(net "GND")
		)
		(pad "T35" smd circle
			(at 9.500108 -8.549894)
			(size 0.4572 0.4572)
			(layers "F.Cu" "F.Mask" "F.Paste")
			(net "P1V8_VDDA_PEX3")
		)
		(pad "T36" smd circle
			(at 10.450068 -8.549894)
			(size 0.4572 0.4572)
			(layers "F.Cu" "F.Mask" "F.Paste")
			(net "Net_529")
		)
		(pad "T37" smd circle
			(at 11.400028 -8.549894)
			(size 0.4572 0.4572)
			(layers "F.Cu" "F.Mask" "F.Paste")
			(net "GND")
		)
		(pad "T38" smd circle
			(at 12.349988 -8.549894)
			(size 0.4572 0.4572)
			(layers "F.Cu" "F.Mask" "F.Paste")
			(net "RST_PEX3_S0_PERST_R_N")
		)
		(pad "T39" smd circle
			(at 13.299948 -8.549894)
			(size 0.4572 0.4572)
			(layers "F.Cu" "F.Mask" "F.Paste")
			(net "Net_389")
		)
		(pad "T40" smd circle
			(at 14.249908 -8.549894)
			(size 0.4572 0.4572)
			(layers "F.Cu" "F.Mask" "F.Paste")
			(net "GND")
		)
		(pad "T41" smd circle
			(at 15.200122 -8.549894)
			(size 0.4572 0.4572)
			(layers "F.Cu" "F.Mask" "F.Paste")
			(net "P5E_PEX3_STN4_TX_DP<64>")
		)
		(pad "T42" smd circle
			(at 16.150082 -8.549894)
			(size 0.4572 0.4572)
			(layers "F.Cu" "F.Mask" "F.Paste")
			(net "P5E_PEX3_STN4_TX_DN<64>")
		)
		(pad "T43" smd circle
			(at 17.100042 -8.549894)
			(size 0.4572 0.4572)
			(layers "F.Cu" "F.Mask" "F.Paste")
			(net "GND")
		)
		(pad "T44" smd circle
			(at 18.050002 -8.549894)
			(size 0.4572 0.4572)
			(layers "F.Cu" "F.Mask" "F.Paste")
			(net "GND")
		)
		(pad "T45" smd circle
			(at 18.999962 -8.549894)
			(size 0.4572 0.4572)
			(layers "F.Cu" "F.Mask" "F.Paste")
			(net "GND")
		)
		(pad "T46" smd circle
			(at 19.949922 -8.549894)
			(size 0.4572 0.4572)
			(layers "F.Cu" "F.Mask" "F.Paste")
			(net "GND")
		)
		(pad "T47" smd circle
			(at 20.899882 -8.549894)
			(size 0.4572 0.4572)
			(layers "F.Cu" "F.Mask" "F.Paste")
			(net "GND")
		)
		(pad "T48" smd circle
			(at 21.850096 -8.549894)
			(size 0.4572 0.4572)
			(layers "F.Cu" "F.Mask" "F.Paste")
			(net "P5E_PEX3_STN4_RX_DP<64>")
		)
		(pad "T49" smd circle
			(at 22.800056 -8.549894)
			(size 0.4572 0.4572)
			(layers "F.Cu" "F.Mask" "F.Paste")
			(net "P5E_PEX3_STN4_RX_DN<64>")
		)
		(pad "U1" smd circle
			(at -22.800056 -7.599934)
			(size 0.4572 0.4572)
			(layers "F.Cu" "F.Mask" "F.Paste")
			(net "GND")
		)
		(pad "U2" smd circle
			(at -21.850096 -7.599934)
			(size 0.4572 0.4572)
			(layers "F.Cu" "F.Mask" "F.Paste")
			(net "GND")
		)
		(pad "U3" smd circle
			(at -20.899882 -7.599934)
			(size 0.4572 0.4572)
			(layers "F.Cu" "F.Mask" "F.Paste")
			(net "P5E_PEX3_STN7_RX_DN<114>")
		)
		(pad "U4" smd circle
			(at -19.949922 -7.599934)
			(size 0.4572 0.4572)
			(layers "F.Cu" "F.Mask" "F.Paste")
			(net "P5E_PEX3_STN7_RX_DP<114>")
		)
		(pad "U5" smd circle
			(at -18.999962 -7.599934)
			(size 0.4572 0.4572)
			(layers "F.Cu" "F.Mask" "F.Paste")
			(net "GND")
		)
		(pad "U6" smd circle
			(at -18.050002 -7.599934)
			(size 0.4572 0.4572)
			(layers "F.Cu" "F.Mask" "F.Paste")
			(net "P5E_PEX3_STN7_TX_DN<114>")
		)
		(pad "U7" smd circle
			(at -17.100042 -7.599934)
			(size 0.4572 0.4572)
			(layers "F.Cu" "F.Mask" "F.Paste")
			(net "P5E_PEX3_STN7_TX_DP<114>")
		)
		(pad "U8" smd circle
			(at -16.150082 -7.599934)
			(size 0.4572 0.4572)
			(layers "F.Cu" "F.Mask" "F.Paste")
			(net "GND")
		)
		(pad "U9" smd circle
			(at -15.200122 -7.599934)
			(size 0.4572 0.4572)
			(layers "F.Cu" "F.Mask" "F.Paste")
			(net "GND")
		)
		(pad "U10" smd circle
			(at -14.249908 -7.599934)
			(size 0.4572 0.4572)
			(layers "F.Cu" "F.Mask" "F.Paste")
			(net "GND")
		)
		(pad "U11" smd circle
			(at -13.299948 -7.599934)
			(size 0.4572 0.4572)
			(layers "F.Cu" "F.Mask" "F.Paste")
			(net "GND")
		)
		(pad "U12" smd circle
			(at -12.349988 -7.599934)
			(size 0.4572 0.4572)
			(layers "F.Cu" "F.Mask" "F.Paste")
			(net "GND")
		)
		(pad "U13" smd circle
			(at -11.400028 -7.599934)
			(size 0.4572 0.4572)
			(layers "F.Cu" "F.Mask" "F.Paste")
			(net "GND")
		)
		(pad "U14" smd circle
			(at -10.450068 -7.599934)
			(size 0.4572 0.4572)
			(layers "F.Cu" "F.Mask" "F.Paste")
			(net "Net_528")
		)
		(pad "U15" smd circle
			(at -9.500108 -7.599934)
			(size 0.4572 0.4572)
			(layers "F.Cu" "F.Mask" "F.Paste")
			(net "GND")
		)
		(pad "U16" smd circle
			(at -8.549894 -7.599934)
			(size 0.4572 0.4572)
			(layers "F.Cu" "F.Mask" "F.Paste")
			(net "GND")
		)
		(pad "U17" smd circle
			(at -7.599934 -7.599934)
			(size 0.4572 0.4572)
			(layers "F.Cu" "F.Mask" "F.Paste")
			(net "GND")
		)
		(pad "U18" smd circle
			(at -6.649974 -7.599934)
			(size 0.4572 0.4572)
			(layers "F.Cu" "F.Mask" "F.Paste")
			(net "GND")
		)
		(pad "U19" smd circle
			(at -5.700014 -7.599934)
			(size 0.4572 0.4572)
			(layers "F.Cu" "F.Mask" "F.Paste")
			(net "GND")
		)
		(pad "U20" smd circle
			(at -4.750054 -7.599934)
			(size 0.4572 0.4572)
			(layers "F.Cu" "F.Mask" "F.Paste")
			(net "GND")
		)
		(pad "U21" smd circle
			(at -3.800094 -7.599934)
			(size 0.4572 0.4572)
			(layers "F.Cu" "F.Mask" "F.Paste")
			(net "GND")
		)
		(pad "U22" smd circle
			(at -2.84988 -7.599934)
			(size 0.4572 0.4572)
			(layers "F.Cu" "F.Mask" "F.Paste")
			(net "GND")
		)
		(pad "U23" smd circle
			(at -1.89992 -7.599934)
			(size 0.4572 0.4572)
			(layers "F.Cu" "F.Mask" "F.Paste")
			(net "GND")
		)
		(pad "U24" smd circle
			(at -0.94996 -7.599934)
			(size 0.4572 0.4572)
			(layers "F.Cu" "F.Mask" "F.Paste")
			(net "GND")
		)
		(pad "U25" smd circle
			(at 0 -7.599934)
			(size 0.4572 0.4572)
			(layers "F.Cu" "F.Mask" "F.Paste")
			(net "GND")
		)
		(pad "U26" smd circle
			(at 0.94996 -7.599934)
			(size 0.4572 0.4572)
			(layers "F.Cu" "F.Mask" "F.Paste")
			(net "GND")
		)
		(pad "U27" smd circle
			(at 1.89992 -7.599934)
			(size 0.4572 0.4572)
			(layers "F.Cu" "F.Mask" "F.Paste")
			(net "GND")
		)
		(pad "U28" smd circle
			(at 2.84988 -7.599934)
			(size 0.4572 0.4572)
			(layers "F.Cu" "F.Mask" "F.Paste")
			(net "GND")
		)
		(pad "U29" smd circle
			(at 3.800094 -7.599934)
			(size 0.4572 0.4572)
			(layers "F.Cu" "F.Mask" "F.Paste")
			(net "GND")
		)
		(pad "U30" smd circle
			(at 4.750054 -7.599934)
			(size 0.4572 0.4572)
			(layers "F.Cu" "F.Mask" "F.Paste")
			(net "GND")
		)
		(pad "U31" smd circle
			(at 5.700014 -7.599934)
			(size 0.4572 0.4572)
			(layers "F.Cu" "F.Mask" "F.Paste")
			(net "GND")
		)
		(pad "U32" smd circle
			(at 6.649974 -7.599934)
			(size 0.4572 0.4572)
			(layers "F.Cu" "F.Mask" "F.Paste")
			(net "GND")
		)
		(pad "U33" smd circle
			(at 7.599934 -7.599934)
			(size 0.4572 0.4572)
			(layers "F.Cu" "F.Mask" "F.Paste")
			(net "GND")
		)
		(pad "U34" smd circle
			(at 8.549894 -7.599934)
			(size 0.4572 0.4572)
			(layers "F.Cu" "F.Mask" "F.Paste")
			(net "GND")
		)
		(pad "U35" smd circle
			(at 9.500108 -7.599934)
			(size 0.4572 0.4572)
			(layers "F.Cu" "F.Mask" "F.Paste")
			(net "GND")
		)
		(pad "U36" smd circle
			(at 10.450068 -7.599934)
			(size 0.4572 0.4572)
			(layers "F.Cu" "F.Mask" "F.Paste")
			(net "Net_533")
		)
	)
)
